#ISCELL
  logical_power bom_note *
  *
#ISCELL
  mstr_misc dns *
  *
#ISCELL
  pure_quanta quanta_title_block_c *
  *
#ISCELL
  logical_power universal_power *
  page13_i1
#ISCELL
  standard offpage *
  page13_i10
#ISCELL
  standard offpage *
  page13_i103
#ISCELL
  standard offpage *
  page13_i104
#ISCELL
  standard offpage *
  page13_i105
#ISCELL
  standard offpage *
  page13_i107
#ISCELL
  standard offpage *
  page13_i108
#ISCELL
  standard offpage *
  page13_i109
#ISCELL
  standard offpage *
  page13_i11
#ISCELL
  standard offpage *
  page13_i110
#ISCELL
  standard offpage *
  page13_i111
#ISCELL
  standard offpage *
  page13_i112
#ISCELL
  standard offpage *
  page13_i113
#ISCELL
  standard offpage *
  page13_i114
#ISCELL
  standard offpage *
  page13_i115
#ISCELL
  standard offpage *
  page13_i12
#ISCELL
  standard offpage *
  page13_i13
#CELL
  pure_quanta q_res *
  page13_i133
#ISCELL
  standard offpage *
  page13_i134
#ISCELL
  standard offpage *
  page13_i14
#ISCELL
  standard offpage *
  page13_i143
#ISCELL
  standard offpage *
  page13_i144
#ISCELL
  standard offpage *
  page13_i145
#ISCELL
  standard offpage *
  page13_i146
#ISCELL
  standard offpage *
  page13_i147
#ISCELL
  standard offpage *
  page13_i15
#ISCELL
  standard offpage *
  page13_i153
#CELL
  pure_quanta q_res *
  page13_i156
#ISCELL
  standard offpage *
  page13_i157
#ISCELL
  standard offpage *
  page13_i158
#CELL
  pure_quanta q_res *
  page13_i159
#CELL
  pure_quanta q_res *
  page13_i16
#CELL
  pure_quanta q_res *
  page13_i17
#CELL
  pure_quanta q_res *
  page13_i18
#ISCELL
  standard offpage *
  page13_i182
#ISCELL
  standard offpage *
  page13_i183
#CELL
  pure_quanta q_res *
  page13_i184
#CELL
  pure_quanta q_res *
  page13_i185
#CELL
  pure_quanta q_res *
  page13_i186
#CELL
  pure_quanta q_res *
  page13_i187
#CELL
  pure_quanta q_res *
  page13_i188
#ISCELL
  standard offpage *
  page13_i189
#ISCELL
  standard offpage *
  page13_i190
#ISCELL
  standard offpage *
  page13_i191
#ISCELL
  standard offpage *
  page13_i192
#ISCELL
  standard offpage *
  page13_i193
#ISCELL
  logical_power universal_power *
  page13_i194
#CELL
  pure_quanta q_res *
  page13_i198
#ISCELL
  standard offpage *
  page13_i199
#ISCELL
  logical_power universal_power *
  page13_i2
#CELL
  pure_quanta q_res *
  page13_i200
#ISCELL
  standard offpage *
  page13_i202
#ISCELL
  standard offpage *
  page13_i203
#CELL
  pure_quanta q_res *
  page13_i204
#ISCELL
  standard offpage *
  page13_i205
#ISCELL
  standard offpage *
  page13_i207
#CELL
  pure_quanta q_res *
  page13_i208
#ISCELL
  standard offpage *
  page13_i209
#ISCELL
  standard offpage *
  page13_i212
#CELL
  pure_quanta q_res *
  page13_i213
#ISCELL
  standard offpage *
  page13_i214
#CELL
  pure_quanta q_res *
  page13_i215
#CELL
  pure_quanta q_res *
  page13_i217
#CELL
  pure_quanta q_res *
  page13_i218
#ISCELL
  standard offpage *
  page13_i219
#ISCELL
  standard offpage *
  page13_i22
#CELL
  pure_quanta q_res *
  page13_i220
#CELL
  pure_quanta q_res *
  page13_i223
#ISCELL
  standard offpage *
  page13_i224
#CELL
  pure_quanta q_res *
  page13_i225
#ISCELL
  standard offpage *
  page13_i226
#CELL
  pure_quanta q_res *
  page13_i227
#ISCELL
  standard offpage *
  page13_i229
#ISCELL
  standard offpage *
  page13_i236
#CELL
  pure_quanta q_res *
  page13_i239
#ISCELL
  standard offpage *
  page13_i24
#ISCELL
  standard offpage *
  page13_i240
#ISCELL
  standard offpage *
  page13_i241
#ISCELL
  standard offpage *
  page13_i242
#ISCELL
  standard offpage *
  page13_i243
#ISCELL
  standard offpage *
  page13_i244
#CELL
  pure_quanta q_res *
  page13_i245
#CELL
  pure_quanta q_res *
  page13_i246
#CELL
  pure_quanta q_res *
  page13_i247
#CELL
  pure_quanta q_res *
  page13_i248
#ISCELL
  standard offpage *
  page13_i26
#CELL
  pure_quanta q_res *
  page13_i266
#ISCELL
  standard offpage *
  page13_i27
#ISCELL
  standard offpage *
  page13_i274
#ISCELL
  standard offpage *
  page13_i275
#CELL
  pure_quanta q_res *
  page13_i278
#CELL
  pure_quanta q_res *
  page13_i279
#ISCELL
  logical_power universal_gnd *
  page13_i28
#ISCELL
  logical_power universal_power *
  page13_i282
#ISCELL
  standard offpage *
  page13_i283
#ISCELL
  standard offpage *
  page13_i284
#CELL
  pure_quanta q_res *
  page13_i286
#ISCELL
  standard offpage *
  page13_i289
#CELL
  pure_quanta q_cap *
  page13_i29
#ISCELL
  standard offpage *
  page13_i290
#CELL
  pure_quanta q_res *
  page13_i295
#ISCELL
  standard offpage *
  page13_i296
#ISCELL
  standard offpage *
  page13_i297
#ISCELL
  standard offpage *
  page13_i298
#CELL
  pure_quanta q_res *
  page13_i299
#CELL
  pure_quanta q_res *
  page13_i3
#CELL
  pure_quanta q_cap *
  page13_i30
#CELL
  pure_quanta q_res *
  page13_i300
#CELL
  pure_quanta q_res *
  page13_i301
#ISCELL
  standard offpage *
  page13_i303
#CELL
  pure_quanta q_res *
  page13_i306
#ISCELL
  standard offpage *
  page13_i307
#ISCELL
  standard offpage *
  page13_i308
#ISCELL
  standard offpage *
  page13_i309
#CELL
  pure_quanta q_cap *
  page13_i31
#CELL
  pure_quanta q_res *
  page13_i312
#ISCELL
  standard offpage *
  page13_i313
#CELL
  pure_quanta q_res *
  page13_i319
#CELL
  pure_quanta q_cap *
  page13_i32
#ISCELL
  standard offpage *
  page13_i320
#CELL
  pure_quanta q_res *
  page13_i33
#ISCELL
  standard offpage *
  page13_i333
#CELL
  pure_quanta q_res *
  page13_i335
#ISCELL
  standard offpage *
  page13_i336
#CELL
  pure_quanta q_res *
  page13_i337
#ISCELL
  standard offpage *
  page13_i338
#CELL
  pure_quanta q_res *
  page13_i339
#ISCELL
  logical_power universal_power *
  page13_i34
#CELL
  pure_quanta q_res *
  page13_i340
#ISCELL
  logical_power universal_gnd *
  page13_i341
#CELL
  pure_quanta q_res *
  page13_i344
#ISCELL
  standard offpage *
  page13_i345
#CELL
  pure_quanta q_res *
  page13_i349
#ISCELL
  logical_power universal_power *
  page13_i35
#CELL
  pure_quanta q_res *
  page13_i350
#CELL
  pure_quanta q_res *
  page13_i351
#ISCELL
  standard offpage *
  page13_i352
#CELL
  pure_quanta q_res *
  page13_i353
#ISCELL
  logical_power universal_power *
  page13_i355
#CELL
  pure_quanta q_res *
  page13_i356
#ISCELL
  standard offpage *
  page13_i358
#ISCELL
  standard offpage *
  page13_i359
#CELL
  pure_quanta q_res *
  page13_i360
#CELL
  pure_quanta ast2600a3gp *
  page13_i363
#ISCELL
  standard offpage *
  page13_i364
#CELL
  pure_quanta q_res *
  page13_i365
#ISCELL
  standard offpage *
  page13_i368
#ISCELL
  standard offpage *
  page13_i369
#ISCELL
  standard offpage *
  page13_i370
#ISCELL
  standard offpage *
  page13_i371
#ISCELL
  standard offpage *
  page13_i372
#CELL
  pure_quanta q_res *
  page13_i373
#CELL
  pure_quanta q_res *
  page13_i374
#CELL
  pure_quanta q_res *
  page13_i381
#CELL
  pure_quanta q_res *
  page13_i382
#CELL
  pure_quanta q_res *
  page13_i383
#CELL
  pure_quanta q_res *
  page13_i384
#ISCELL
  standard offpage *
  page13_i392
#ISCELL
  standard offpage *
  page13_i393
#ISCELL
  standard offpage *
  page13_i394
#ISCELL
  standard offpage *
  page13_i395
#ISCELL
  standard offpage *
  page13_i396
#CELL
  pure_quanta q_res *
  page13_i398
#CELL
  pure_quanta q_res *
  page13_i399
#CELL
  pure_quanta q_res *
  page13_i4
#CELL
  pure_quanta q_res *
  page13_i400
#CELL
  pure_quanta q_res *
  page13_i402
#ISCELL
  standard offpage *
  page13_i403
#ISCELL
  standard offpage *
  page13_i404
#ISCELL
  standard offpage *
  page13_i405
#ISCELL
  standard offpage *
  page13_i406
#CELL
  pure_quanta q_res *
  page13_i407
#ISCELL
  standard offpage *
  page13_i409
#ISCELL
  standard offpage *
  page13_i413
#ISCELL
  standard offpage *
  page13_i414
#ISCELL
  standard offpage *
  page13_i415
#ISCELL
  standard offpage *
  page13_i417
#CELL
  pure_quanta q_res *
  page13_i419
#ISCELL
  standard offpage *
  page13_i420
#CELL
  pure_quanta q_res *
  page13_i421
#ISCELL
  standard offpage *
  page13_i422
#ISCELL
  standard offpage *
  page13_i426
#CELL
  pure_quanta q_res *
  page13_i427
#ISCELL
  standard offpage *
  page13_i428
#ISCELL
  standard offpage *
  page13_i429
#CELL
  pure_quanta q_res *
  page13_i430
#CELL
  pure_quanta q_res *
  page13_i431
#CELL
  pure_quanta q_res *
  page13_i432
#ISCELL
  standard offpage *
  page13_i433
#ISCELL
  standard offpage *
  page13_i434
#CELL
  pure_quanta 74lvc1g66gv *
  page13_i435
#ISCELL
  standard offpage *
  page13_i436
#ISCELL
  logical_power universal_gnd *
  page13_i439
#CELL
  pure_quanta q_cap *
  page13_i440
#ISCELL
  logical_power vccaux15 *
  page13_i441
#ISCELL
  logical_power universal_gnd *
  page13_i442
#ISCELL
  standard offpage *
  page13_i443
#ISCELL
  standard offpage *
  page13_i446
#CELL
  pure_quanta q_res *
  page13_i447
#CELL
  pure_quanta q_res *
  page13_i448
#CELL
  pure_quanta q_res *
  page13_i449
#CELL
  pure_quanta q_res *
  page13_i451
#CELL
  pure_quanta q_res *
  page13_i452
#CELL
  pure_quanta q_res *
  page13_i453
#CELL
  pure_quanta q_led *
  page13_i46
#ISCELL
  standard offpage *
  page13_i48
#CELL
  pure_quanta q_res *
  page13_i5
#CELL
  pure_quanta q_res *
  page13_i50
#ISCELL
  standard offpage *
  page13_i55
#ISCELL
  logical_power universal_power *
  page13_i6
#CELL
  pure_quanta q_res *
  page13_i67
#ISCELL
  standard offpage *
  page13_i69
#ISCELL
  standard offpage *
  page13_i7
#ISCELL
  standard offpage *
  page13_i76
#ISCELL
  standard offpage *
  page13_i77
#ISCELL
  standard offpage *
  page13_i78
#ISCELL
  standard offpage *
  page13_i79
#ISCELL
  standard offpage *
  page13_i8
#ISCELL
  standard offpage *
  page13_i80
#CELL
  pure_quanta q_res *
  page13_i87
#ISCELL
  standard offpage *
  page13_i9
#ISCELL
  standard offpage *
  page13_i91
#CELL
  pure_quanta q_res *
  page13_i94
#CELL
  pure_quanta q_res *
  page13_i95
#CELL
  pure_quanta q_res *
  page13_i96
#ISCELL
  standard offpage *
  page13_i97
